(kicad_pcb
	(version 20260206)
	(generator "pcbnew")
	(generator_version "10.0")
	(general
		(thickness 1.6)
		(legacy_teardrops no)
	)
	(paper "A4")
	(title_block
		(title "baseboard — 13948-1b.1110WZS1818.brd")
		(comment 1 "Honey Badger (Wiwynn) / footprints 419-425 of 2523")
	)
	(layers
		(0 "F.Cu" signal "TOP")
		(4 "In1.Cu" signal "L2GND")
		(6 "In2.Cu" signal "L3")
		(8 "In3.Cu" signal "L4VCC")
		(10 "In4.Cu" signal "L5VCC")
		(12 "In5.Cu" signal "L6")
		(14 "In6.Cu" signal "L7GND")
		(2 "B.Cu" signal "BOTTOM")
		(9 "F.Adhes" user "F.Adhesive")
		(11 "B.Adhes" user "B.Adhesive")
		(13 "F.Paste" user "Package Geometry/Pastemask Top")
		(15 "B.Paste" user "Package Geometry/Pastemask Bottom")
		(5 "F.SilkS" user "Ref Des/Silkscreen Top")
		(7 "B.SilkS" user "Ref Des/Silkscreen Bottom")
		(1 "F.Mask" user "Board Geometry/Soldermask Top")
		(3 "B.Mask" user "Board Geometry/Soldermask Bottom")
		(17 "Dwgs.User" user "User.Drawings")
		(19 "Cmts.User" user "User.Comments")
		(21 "Eco1.User" user "User.Eco1")
		(23 "Eco2.User" user "User.Eco2")
		(25 "Edge.Cuts" user "Board Geometry/Outline")
		(27 "Margin" user)
		(31 "F.CrtYd" user "Package Geometry/Place Bound Top")
		(29 "B.CrtYd" user "Package Geometry/Place Bound Bottom")
		(35 "F.Fab" user "Ref Des/Assembly Top")
		(33 "B.Fab" user "Ref Des/Assembly Bottom")
	)
	(footprint ""
		(layer "F.Cu")
		(at 86.49716 -36.957 -90)
		(property "Reference" "SC883"
			(at 0 0 270)
			(layer "F.SilkS")
			(hide yes)
			(effects
				(font
					(size 1.27 1.27)
				)
			)
		)
		(property "Value" "SCD01U10V1KX-GP"
			(at -2.8321 -1.7399 270)
			(unlocked yes)
			(layer "F.Fab")
			(hide yes)
			(effects
				(font
					(size 1.016 1.016)
					(thickness 0.1524)
				)
			)
		)
		(property "Device Type" "C0201H13"
			(at -2.8321 -3.2639 270)
			(unlocked yes)
			(layer "F.Fab")
			(hide yes)
			(effects
				(font
					(size 1.016 1.016)
					(thickness 0.1524)
				)
			)
		)
		(duplicate_pad_numbers_are_jumpers no)
		(fp_rect
			(start -0.2794 0.6477)
			(end 0.2794 -0.6477)
			(stroke
				(width 0)
				(type default)
			)
			(fill no)
			(layer "F.CrtYd")
		)
		(fp_rect
			(start -0.2794 0.6477)
			(end 0.2794 -0.6477)
			(stroke
				(width 0)
				(type default)
			)
			(fill no)
			(layer "F.Fab")
		)
		(pad "1" smd custom
			(at 0 -0.2794 270)
			(size 0.0762 0.0762)
			(layers "F.Cu" "F.Mask" "F.Paste")
			(net "SAS3008_RAID_TX_C_P2")
			(options
				(clearance outline)
				(anchor circle)
			)
			(primitives
				(gr_poly
					(pts
						(arc
							(start 0.1524 -0.127)
							(mid 0.137521 -0.162921)
							(end 0.1016 -0.1778)
						)
						(arc
							(start -0.1016 -0.1778)
							(mid -0.137521 -0.162921)
							(end -0.1524 -0.127)
						)
						(arc
							(start -0.1524 0.127)
							(mid -0.137521 0.162921)
							(end -0.1016 0.1778)
						)
						(arc
							(start 0.1016 0.1778)
							(mid 0.137521 0.162921)
							(end 0.1524 0.127)
						)
					)
					(width 0)
					(fill yes)
				)
			)
		)
		(pad "2" smd custom
			(at 0 0.2794 270)
			(size 0.0762 0.0762)
			(layers "F.Cu" "F.Mask" "F.Paste")
			(net "SAS3008_RAID_TX_P2")
			(options
				(clearance outline)
				(anchor circle)
			)
			(primitives
				(gr_poly
					(pts
						(arc
							(start 0.1524 -0.127)
							(mid 0.137521 -0.162921)
							(end 0.1016 -0.1778)
						)
						(arc
							(start -0.1016 -0.1778)
							(mid -0.137521 -0.162921)
							(end -0.1524 -0.127)
						)
						(arc
							(start -0.1524 0.127)
							(mid -0.137521 0.162921)
							(end -0.1016 0.1778)
						)
						(arc
							(start 0.1016 0.1778)
							(mid 0.137521 0.162921)
							(end 0.1524 0.127)
						)
					)
					(width 0)
					(fill yes)
				)
			)
		)
	)
	(footprint ""
		(layer "F.Cu")
		(at 174.179992 -25.781)
		(property "Reference" "C235"
			(at 0 0 0)
			(layer "F.SilkS")
			(hide yes)
			(effects
				(font
					(size 1.27 1.27)
				)
			)
		)
		(property "Value" "SC27P50V2JN-2DLGP"
			(at 1.1811 -2.7051 0)
			(unlocked yes)
			(layer "F.Fab")
			(hide yes)
			(effects
				(font
					(size 1.016 1.016)
					(thickness 0.1524)
				)
			)
		)
		(property "Device Type" "C402H22"
			(at 1.1811 -4.2291 0)
			(unlocked yes)
			(layer "F.Fab")
			(hide yes)
			(effects
				(font
					(size 1.016 1.016)
					(thickness 0.1524)
				)
			)
		)
		(duplicate_pad_numbers_are_jumpers no)
		(fp_rect
			(start -0.4318 0.9525)
			(end 0.4318 -0.9525)
			(stroke
				(width 0)
				(type default)
			)
			(fill no)
			(layer "F.CrtYd")
		)
		(fp_rect
			(start -0.4318 0.9525)
			(end 0.4318 -0.9525)
			(stroke
				(width 0)
				(type default)
			)
			(fill no)
			(layer "F.Fab")
		)
		(pad "1" smd custom
			(at 0 -0.4445)
			(size 0.1524 0.1524)
			(layers "F.Cu" "F.Mask" "F.Paste")
			(net "BCM5221_TX_C_DN")
			(options
				(clearance outline)
				(anchor circle)
			)
			(primitives
				(gr_poly
					(pts
						(arc
							(start 0.3048 -0.2032)
							(mid 0.275042 -0.275042)
							(end 0.2032 -0.3048)
						)
						(arc
							(start -0.2032 -0.3048)
							(mid -0.275042 -0.275042)
							(end -0.3048 -0.2032)
						)
						(arc
							(start -0.3048 0.2032)
							(mid -0.275042 0.275042)
							(end -0.2032 0.3048)
						)
						(arc
							(start 0.2032 0.3048)
							(mid 0.275042 0.275042)
							(end 0.3048 0.2032)
						)
					)
					(width 0)
					(fill yes)
				)
			)
		)
		(pad "2" smd custom
			(at 0 0.4445)
			(size 0.1524 0.1524)
			(layers "F.Cu" "F.Mask" "F.Paste")
			(net "BCM5221_TX_C_DP")
			(options
				(clearance outline)
				(anchor circle)
			)
			(primitives
				(gr_poly
					(pts
						(arc
							(start 0.3048 -0.2032)
							(mid 0.275042 -0.275042)
							(end 0.2032 -0.3048)
						)
						(arc
							(start -0.2032 -0.3048)
							(mid -0.275042 -0.275042)
							(end -0.3048 -0.2032)
						)
						(arc
							(start -0.3048 0.2032)
							(mid -0.275042 0.275042)
							(end -0.2032 0.3048)
						)
						(arc
							(start 0.2032 0.3048)
							(mid 0.275042 0.275042)
							(end 0.3048 0.2032)
						)
					)
					(width 0)
					(fill yes)
				)
			)
		)
	)
	(footprint ""
		(layer "F.Cu")
		(at 336.169 -113.538)
		(property "Reference" "PR16"
			(at 0 0 0)
			(layer "F.SilkS")
			(hide yes)
			(effects
				(font
					(size 1.27 1.27)
				)
			)
		)
		(property "Value" "5K36R2F-GP"
			(at 0.064008 -3.993896 0)
			(unlocked yes)
			(layer "F.Fab")
			(hide yes)
			(effects
				(font
					(size 1.016 1.016)
					(thickness 0.1524)
				)
			)
		)
		(property "Device Type" "R402H16"
			(at 0.064008 -5.517896 0)
			(unlocked yes)
			(layer "F.Fab")
			(hide yes)
			(effects
				(font
					(size 1.016 1.016)
					(thickness 0.1524)
				)
			)
		)
		(duplicate_pad_numbers_are_jumpers no)
		(fp_line
			(start -0.508 -0.9398)
			(end -0.508 0.9398)
			(stroke
				(width 0.1524)
				(type default)
			)
			(layer "F.SilkS")
		)
		(fp_line
			(start 0.508 -0.9398)
			(end -0.508 -0.9398)
			(stroke
				(width 0.1524)
				(type default)
			)
			(layer "F.SilkS")
		)
		(fp_rect
			(start -0.508 0.9398)
			(end 0.508 -0.9398)
			(stroke
				(width 0)
				(type default)
			)
			(fill no)
			(layer "F.CrtYd")
		)
		(fp_rect
			(start -0.508 0.9398)
			(end 0.508 -0.9398)
			(stroke
				(width 0)
				(type default)
			)
			(fill no)
			(layer "F.Fab")
		)
		(pad "1" smd custom
			(at 0 -0.4445)
			(size 0.1397 0.1397)
			(layers "F.Cu" "F.Mask" "F.Paste")
			(net "P12V")
			(options
				(clearance outline)
				(anchor circle)
			)
			(primitives
				(gr_poly
					(pts
						(arc
							(start -0.1778 -0.2794)
							(mid -0.249642 -0.249642)
							(end -0.2794 -0.1778)
						)
						(arc
							(start -0.2794 0.1778)
							(mid -0.249642 0.249642)
							(end -0.1778 0.2794)
						)
						(arc
							(start 0.1778 0.2794)
							(mid 0.249642 0.249642)
							(end 0.2794 0.1778)
						)
						(arc
							(start 0.2794 -0.1778)
							(mid 0.249642 -0.249642)
							(end 0.1778 -0.2794)
						)
					)
					(width 0)
					(fill yes)
				)
			)
		)
		(pad "2" smd custom
			(at 0 0.4445)
			(size 0.1397 0.1397)
			(layers "F.Cu" "F.Mask" "F.Paste")
			(net "P5V_STBY_EN_R")
			(options
				(clearance outline)
				(anchor circle)
			)
			(primitives
				(gr_poly
					(pts
						(arc
							(start -0.1778 -0.2794)
							(mid -0.249642 -0.249642)
							(end -0.2794 -0.1778)
						)
						(arc
							(start -0.2794 0.1778)
							(mid -0.249642 0.249642)
							(end -0.1778 0.2794)
						)
						(arc
							(start 0.1778 0.2794)
							(mid 0.249642 0.249642)
							(end 0.2794 0.1778)
						)
						(arc
							(start 0.2794 -0.1778)
							(mid 0.249642 -0.249642)
							(end 0.1778 -0.2794)
						)
					)
					(width 0)
					(fill yes)
				)
			)
		)
	)
	(footprint ""
		(layer "F.Cu")
		(at 309.88 -205.105)
		(property "Reference" "R5301"
			(at 0 0 0)
			(layer "F.SilkS")
			(hide yes)
			(effects
				(font
					(size 1.27 1.27)
				)
			)
		)
		(property "Value" "0R2J-2-GP"
			(at 0.064008 -3.993896 0)
			(unlocked yes)
			(layer "F.Fab")
			(hide yes)
			(effects
				(font
					(size 1.016 1.016)
					(thickness 0.1524)
				)
			)
		)
		(property "Device Type" "R402H16"
			(at 0.064008 -5.517896 0)
			(unlocked yes)
			(layer "F.Fab")
			(hide yes)
			(effects
				(font
					(size 1.016 1.016)
					(thickness 0.1524)
				)
			)
		)
		(duplicate_pad_numbers_are_jumpers no)
		(fp_line
			(start -0.508 -0.9398)
			(end -0.508 0.9398)
			(stroke
				(width 0.1524)
				(type default)
			)
			(layer "F.SilkS")
		)
		(fp_line
			(start 0.508 -0.9398)
			(end -0.508 -0.9398)
			(stroke
				(width 0.1524)
				(type default)
			)
			(layer "F.SilkS")
		)
		(fp_rect
			(start -0.508 0.9398)
			(end 0.508 -0.9398)
			(stroke
				(width 0)
				(type default)
			)
			(fill no)
			(layer "F.CrtYd")
		)
		(fp_rect
			(start -0.508 0.9398)
			(end 0.508 -0.9398)
			(stroke
				(width 0)
				(type default)
			)
			(fill no)
			(layer "F.Fab")
		)
		(pad "1" smd custom
			(at 0 -0.4445)
			(size 0.1397 0.1397)
			(layers "F.Cu" "F.Mask" "F.Paste")
			(net "BMC_I2C_SCL_10")
			(options
				(clearance outline)
				(anchor circle)
			)
			(primitives
				(gr_poly
					(pts
						(arc
							(start -0.1778 -0.2794)
							(mid -0.249642 -0.249642)
							(end -0.2794 -0.1778)
						)
						(arc
							(start -0.2794 0.1778)
							(mid -0.249642 0.249642)
							(end -0.1778 0.2794)
						)
						(arc
							(start 0.1778 0.2794)
							(mid 0.249642 0.249642)
							(end 0.2794 0.1778)
						)
						(arc
							(start 0.2794 -0.1778)
							(mid 0.249642 -0.249642)
							(end 0.1778 -0.2794)
						)
					)
					(width 0)
					(fill yes)
				)
			)
		)
		(pad "2" smd custom
			(at 0 0.4445)
			(size 0.1397 0.1397)
			(layers "F.Cu" "F.Mask" "F.Paste")
			(net "LED_DR_I2C_SCL")
			(options
				(clearance outline)
				(anchor circle)
			)
			(primitives
				(gr_poly
					(pts
						(arc
							(start -0.1778 -0.2794)
							(mid -0.249642 -0.249642)
							(end -0.2794 -0.1778)
						)
						(arc
							(start -0.2794 0.1778)
							(mid -0.249642 0.249642)
							(end -0.1778 0.2794)
						)
						(arc
							(start 0.1778 0.2794)
							(mid 0.249642 0.249642)
							(end 0.2794 0.1778)
						)
						(arc
							(start 0.2794 -0.1778)
							(mid 0.249642 -0.249642)
							(end 0.1778 -0.2794)
						)
					)
					(width 0)
					(fill yes)
				)
			)
		)
	)
	(footprint ""
		(layer "F.Cu")
		(at 52.08397 -141.097 -90)
		(property "Reference" "SU79"
			(at 0 0 270)
			(layer "F.SilkS")
			(hide yes)
			(effects
				(font
					(size 1.27 1.27)
				)
			)
		)
		(property "Value" "SN74LVC1G08DCKR-GP"
			(at -2.3368 -8.6868 270)
			(unlocked yes)
			(layer "F.Fab")
			(hide yes)
			(effects
				(font
					(size 1.016 1.016)
					(thickness 0.1524)
				)
			)
		)
		(property "Device Type" "SC70-5H44"
			(at -2.3114 -10.414 270)
			(unlocked yes)
			(layer "F.Fab")
			(hide yes)
			(effects
				(font
					(size 1.016 1.016)
					(thickness 0.1524)
				)
			)
		)
		(duplicate_pad_numbers_are_jumpers no)
		(fp_line
			(start -1.27 1.7018)
			(end -1.27 -1.7018)
			(stroke
				(width 0.1524)
				(type default)
			)
			(layer "F.SilkS")
		)
		(fp_line
			(start 1.27 1.7018)
			(end -1.27 1.7018)
			(stroke
				(width 0.1524)
				(type default)
			)
			(layer "F.SilkS")
		)
		(fp_line
			(start -1.27 -1.7018)
			(end 1.27 -1.7018)
			(stroke
				(width 0.1524)
				(type default)
			)
			(layer "F.SilkS")
		)
		(fp_line
			(start 1.27 -1.7018)
			(end 1.27 1.7018)
			(stroke
				(width 0.1524)
				(type default)
			)
			(layer "F.SilkS")
		)
		(fp_line
			(start 0.6604 -1.8034)
			(end 1.3843 -1.8034)
			(stroke
				(width 0.3302)
				(type default)
			)
			(layer "F.SilkS")
		)
		(fp_line
			(start 1.3843 -1.8034)
			(end 1.3843 -1.1176)
			(stroke
				(width 0.3302)
				(type default)
			)
			(layer "F.SilkS")
		)
		(fp_rect
			(start -1.524 1.9558)
			(end 1.524 -1.9558)
			(stroke
				(width 0)
				(type default)
			)
			(fill no)
			(layer "F.CrtYd")
		)
		(fp_poly
			(pts
				(xy -1.524 -1.9558) (xy 1.524 -1.9558) (xy 1.524 1.9558) (xy -1.524 1.9558)
			)
			(stroke
				(width 0)
				(type default)
			)
			(fill no)
			(layer "F.Fab")
		)
		(pad "1" smd rect
			(at 0.65024 -0.8255 270)
			(size 0.4064 1.2192)
			(layers "F.Cu" "F.Mask" "F.Paste")
			(net "RST_BTN_N")
		)
		(pad "2" smd rect
			(at 0 -0.8255 270)
			(size 0.4064 1.2192)
			(layers "F.Cu" "F.Mask" "F.Paste")
			(net "DP_EXP_RST")
		)
		(pad "3" smd rect
			(at -0.65024 -0.8255 270)
			(size 0.4064 1.2192)
			(layers "F.Cu" "F.Mask" "F.Paste")
			(net "GND")
		)
		(pad "4" smd rect
			(at -0.65024 0.8255 270)
			(size 0.4064 1.2192)
			(layers "F.Cu" "F.Mask" "F.Paste")
			(net "EXP_RST_2")
		)
		(pad "5" smd rect
			(at 0.65024 0.8255 270)
			(size 0.4064 1.2192)
			(layers "F.Cu" "F.Mask" "F.Paste")
			(net "P1V8_E")
		)
	)
	(footprint ""
		(layer "F.Cu")
		(at 291.084 -161.544)
		(property "Reference" "R474"
			(at 0 0 0)
			(layer "F.SilkS")
			(hide yes)
			(effects
				(font
					(size 1.27 1.27)
				)
			)
		)
		(property "Value" "0R2J-2-GP"
			(at 0.064008 -3.993896 0)
			(unlocked yes)
			(layer "F.Fab")
			(hide yes)
			(effects
				(font
					(size 1.016 1.016)
					(thickness 0.1524)
				)
			)
		)
		(property "Device Type" "R402H16"
			(at 0.064008 -5.517896 0)
			(unlocked yes)
			(layer "F.Fab")
			(hide yes)
			(effects
				(font
					(size 1.016 1.016)
					(thickness 0.1524)
				)
			)
		)
		(duplicate_pad_numbers_are_jumpers no)
		(fp_line
			(start -0.508 -0.9398)
			(end -0.508 0.9398)
			(stroke
				(width 0.1524)
				(type default)
			)
			(layer "F.SilkS")
		)
		(fp_line
			(start 0.508 -0.9398)
			(end -0.508 -0.9398)
			(stroke
				(width 0.1524)
				(type default)
			)
			(layer "F.SilkS")
		)
		(fp_rect
			(start -0.508 0.9398)
			(end 0.508 -0.9398)
			(stroke
				(width 0)
				(type default)
			)
			(fill no)
			(layer "F.CrtYd")
		)
		(fp_rect
			(start -0.508 0.9398)
			(end 0.508 -0.9398)
			(stroke
				(width 0)
				(type default)
			)
			(fill no)
			(layer "F.Fab")
		)
		(pad "1" smd custom
			(at 0 -0.4445)
			(size 0.1397 0.1397)
			(layers "F.Cu" "F.Mask" "F.Paste")
			(net "BMC_RXD1")
			(options
				(clearance outline)
				(anchor circle)
			)
			(primitives
				(gr_poly
					(pts
						(arc
							(start -0.1778 -0.2794)
							(mid -0.249642 -0.249642)
							(end -0.2794 -0.1778)
						)
						(arc
							(start -0.2794 0.1778)
							(mid -0.249642 0.249642)
							(end -0.1778 0.2794)
						)
						(arc
							(start 0.1778 0.2794)
							(mid 0.249642 0.249642)
							(end 0.2794 0.1778)
						)
						(arc
							(start 0.2794 -0.1778)
							(mid 0.249642 -0.249642)
							(end 0.1778 -0.2794)
						)
					)
					(width 0)
					(fill yes)
				)
			)
		)
		(pad "2" smd custom
			(at 0 0.4445)
			(size 0.1397 0.1397)
			(layers "F.Cu" "F.Mask" "F.Paste")
			(net "CPU_BMC_UART_RX")
			(options
				(clearance outline)
				(anchor circle)
			)
			(primitives
				(gr_poly
					(pts
						(arc
							(start -0.1778 -0.2794)
							(mid -0.249642 -0.249642)
							(end -0.2794 -0.1778)
						)
						(arc
							(start -0.2794 0.1778)
							(mid -0.249642 0.249642)
							(end -0.1778 0.2794)
						)
						(arc
							(start 0.1778 0.2794)
							(mid 0.249642 0.249642)
							(end 0.2794 0.1778)
						)
						(arc
							(start 0.2794 -0.1778)
							(mid 0.249642 -0.249642)
							(end 0.1778 -0.2794)
						)
					)
					(width 0)
					(fill yes)
				)
			)
		)
	)
	(footprint ""
		(layer "F.Cu")
		(at 317.754 -120.523 180)
		(property "Reference" "PR25"
			(at 0 0 180)
			(layer "F.SilkS")
			(hide yes)
			(effects
				(font
					(size 1.27 1.27)
				)
			)
		)
		(property "Value" "10KR2F-2-GP"
			(at 0.064008 -3.993896 180)
			(unlocked yes)
			(layer "F.Fab")
			(hide yes)
			(effects
				(font
					(size 1.016 1.016)
					(thickness 0.1524)
				)
			)
		)
		(property "Device Type" "R402H16"
			(at 0.064008 -5.517896 180)
			(unlocked yes)
			(layer "F.Fab")
			(hide yes)
			(effects
				(font
					(size 1.016 1.016)
					(thickness 0.1524)
				)
			)
		)
		(duplicate_pad_numbers_are_jumpers no)
		(fp_line
			(start 0.508 -0.9398)
			(end -0.508 -0.9398)
			(stroke
				(width 0.1524)
				(type default)
			)
			(layer "F.SilkS")
		)
		(fp_line
			(start -0.508 -0.9398)
			(end -0.508 0.9398)
			(stroke
				(width 0.1524)
				(type default)
			)
			(layer "F.SilkS")
		)
		(fp_rect
			(start -0.508 0.9398)
			(end 0.508 -0.9398)
			(stroke
				(width 0)
				(type default)
			)
			(fill no)
			(layer "F.CrtYd")
		)
		(fp_rect
			(start -0.508 0.9398)
			(end 0.508 -0.9398)
			(stroke
				(width 0)
				(type default)
			)
			(fill no)
			(layer "F.Fab")
		)
		(pad "1" smd custom
			(at 0 -0.4445 180)
			(size 0.1397 0.1397)
			(layers "F.Cu" "F.Mask" "F.Paste")
			(net "P3V3_STBY_PG")
			(options
				(clearance outline)
				(anchor circle)
			)
			(primitives
				(gr_poly
					(pts
						(arc
							(start -0.1778 -0.2794)
							(mid -0.249642 -0.249642)
							(end -0.2794 -0.1778)
						)
						(arc
							(start -0.2794 0.1778)
							(mid -0.249642 0.249642)
							(end -0.1778 0.2794)
						)
						(arc
							(start 0.1778 0.2794)
							(mid 0.249642 0.249642)
							(end 0.2794 0.1778)
						)
						(arc
							(start 0.2794 -0.1778)
							(mid 0.249642 -0.249642)
							(end 0.1778 -0.2794)
						)
					)
					(width 0)
					(fill yes)
				)
			)
		)
		(pad "2" smd custom
			(at 0 0.4445 180)
			(size 0.1397 0.1397)
			(layers "F.Cu" "F.Mask" "F.Paste")
			(net "P3V3_STBY_VREG")
			(options
				(clearance outline)
				(anchor circle)
			)
			(primitives
				(gr_poly
					(pts
						(arc
							(start -0.1778 -0.2794)
							(mid -0.249642 -0.249642)
							(end -0.2794 -0.1778)
						)
						(arc
							(start -0.2794 0.1778)
							(mid -0.249642 0.249642)
							(end -0.1778 0.2794)
						)
						(arc
							(start 0.1778 0.2794)
							(mid 0.249642 0.249642)
							(end 0.2794 0.1778)
						)
						(arc
							(start 0.2794 -0.1778)
							(mid 0.249642 -0.249642)
							(end 0.1778 -0.2794)
						)
					)
					(width 0)
					(fill yes)
				)
			)
		)
	)
)
